# T6G (Grand Teton) — schematic netlist excerpt (pin names and nets, part order shuffled) for the footprints in the layout excerpt that follows; sources: Cadence DE-HDL packaged netlist, KiCad conversion of 04192023_DAF0TMB3IC0_F0TG_MB_C_brd_V02_OCP.brd

J29  SCONN288_DDR506112002KQ  IO  pkg DDR288S_1-1VXC  page 107
  VIN_BULK0  = P12V_MEM_CPU1
  RFU0  = NC
  VIN_MGMT  = P3V3_AUX
  HSCL  = I3C_SPD_DDRJ_CPU1_SCL
  HSDA  = I3C_SPD_DDRJ_CPU1_SDA
  VSS0  = GND
  DQ0_A  = M_J_CPU1_SA_DQ<0>
  VSS1  = GND
  DQ1_A  = M_J_CPU1_SA_DQ<1>
  VSS2  = GND
  DQS0_A_T  = M_J_CPU1_SA_DQS_DP<0>
  DQS0_A_C  = M_J_CPU1_SA_DQS_DN<0>
  VSS3  = GND
  DQ4_A  = M_J_CPU1_SA_DQ<4>
  VSS4  = GND
  DQ5_A  = M_J_CPU1_SA_DQ<5>
  VSS5  = GND
  DQ8_A  = M_J_CPU1_SA_DQ<8>
  VSS6  = GND
  DQ9_A  = M_J_CPU1_SA_DQ<9>
  VSS7  = GND
  DQS1_A_T  = M_J_CPU1_SA_DQS_DP<1>
  DQS1_A_C  = M_J_CPU1_SA_DQS_DN<1>
  VSS8  = GND
  DQ12_A  = M_J_CPU1_SA_DQ<12>
  VSS9  = GND
  DQ13_A  = M_J_CPU1_SA_DQ<13>
  VSS10  = GND
  DQ16_A  = M_J_CPU1_SA_DQ<16>
  VSS11  = GND
  DQ17_A  = M_J_CPU1_SA_DQ<17>
  VSS12  = GND
  DQS2_A_T  = M_J_CPU1_SA_DQS_DP<2>
  DQS2_A_C  = M_J_CPU1_SA_DQS_DN<2>
  VSS13  = GND
  DQ20_A  = M_J_CPU1_SA_DQ<20>
  VSS14  = GND
  DQ21_A  = M_J_CPU1_SA_DQ<21>
  VSS15  = GND
  DQ24_A  = M_J_CPU1_SA_DQ<24>
  VSS16  = GND
  DQ25_A  = M_J_CPU1_SA_DQ<25>
  VSS17  = GND
  DQS3_A_T  = M_J_CPU1_SA_DQS_DP<3>
  DQS3_A_C  = M_J_CPU1_SA_DQS_DN<3>
  VSS18  = GND
  DQ28_A  = M_J_CPU1_SA_DQ<28>
  VSS19  = GND
  DQ29_A  = M_J_CPU1_SA_DQ<29>
  VSS20  = GND
  CB0_A  = M_J_CPU1_SA_CB<0>
  VSS21  = GND
  CB1_A  = M_J_CPU1_SA_CB<1>
  VSS22  = GND
  DQS4_A_T  = M_J_CPU1_SA_DQS_DP<4>
  DQS4_A_C  = M_J_CPU1_SA_DQS_DN<4>
  VSS23  = GND
  CB4_A  = M_J_CPU1_SA_CB<4>
  VSS24  = GND
  CB5_A  = M_J_CPU1_SA_CB<5>
  VSS25  = GND
  ALERT_N  = M_J_CPU1_ALERT_N
  VSS26  = GND
  CS0_A_N  = M_J_CPU1_SA_CS_N<0>
  VSS27  = GND
  CA0_A  = M_J_CPU1_SA_CA<0>
  VSS28  = GND
  CA2_A  = M_J_CPU1_SA_CA<2>
  VSS29  = GND
  CA4_A  = M_J_CPU1_SA_CA<4>
  VSS30  = GND
  CA6_A  = M_J_CPU1_SA_CA<6>
  VSS31  = GND
  PAR_A  = M_J_CPU1_SA_PAR
  VSS32  = GND
  CA0_B  = M_J_CPU1_SB_CA<0>
  VSS33  = GND
  CA2_B  = M_J_CPU1_SB_CA<2>
  VSS34  = GND
  CA4_B  = M_J_CPU1_SB_CA<4>
  VSS35  = GND
  CA6_B  = M_J_CPU1_SB_CA<6>
  VSS36  = GND
  CS0_B_N  = M_J_CPU1_SB_CS_N<0>
  VSS37  = GND
  \lbd||rsp_a_n\  = M_J_CPU1_SA_RSP<0>
  \lbs||rsp_b_n\  = M_J_CPU1_SB_RSP<0>
  VSS38  = GND
  CB4_B  = M_J_CPU1_SB_CB<4>
  VSS39  = GND
  CB5_B  = M_J_CPU1_SB_CB<5>
  VSS40  = GND
  \dqs9_b_t||tdqs9_b_t||dbi4_b_n\  = M_J_CPU1_SB_DQS_DP<9>
  \dqs9_b_c||tdqs9_b_c\  = M_J_CPU1_SB_DQS_DN<9>
  VSS41  = GND
  CB0_B  = M_J_CPU1_SB_CB<0>
  VSS42  = GND
  CB1_B  = M_J_CPU1_SB_CB<1>
  VSS43  = GND
  DQ0_B  = M_J_CPU1_SB_DQ<0>
  VSS44  = GND
  DQ1_B  = M_J_CPU1_SB_DQ<1>
  VSS45  = GND
  DQS0_B_T  = M_J_CPU1_SB_DQS_DP<0>
  DQS0_B_C  = M_J_CPU1_SB_DQS_DN<0>
  VSS46  = GND
  DQ4_B  = M_J_CPU1_SB_DQ<4>
  VSS47  = GND
  DQ5_B  = M_J_CPU1_SB_DQ<5>
  VSS48  = GND
  DQ8_B  = M_J_CPU1_SB_DQ<8>
  VSS49  = GND
  DQ9_B  = M_J_CPU1_SB_DQ<9>
  VSS50  = GND
  DQS1_B_T  = M_J_CPU1_SB_DQS_DP<1>
  DQS1_B_C  = M_J_CPU1_SB_DQS_DN<1>
  VSS51  = GND
  DQ12_B  = M_J_CPU1_SB_DQ<12>
  VSS52  = GND
  DQ13_B  = M_J_CPU1_SB_DQ<13>
  VSS53  = GND
  DQ16_B  = M_J_CPU1_SB_DQ<16>
  VSS54  = GND
  DQ17_B  = M_J_CPU1_SB_DQ<17>
  VSS55  = GND
  DQS2_B_T  = M_J_CPU1_SB_DQS_DP<2>
  DQS2_B_C  = M_J_CPU1_SB_DQS_DN<2>
  VSS56  = GND
  DQ20_B  = M_J_CPU1_SB_DQ<20>
  VSS57  = GND
  DQ21_B  = M_J_CPU1_SB_DQ<21>
  VSS58  = GND
  DQ24_B  = M_J_CPU1_SB_DQ<24>
  VSS59  = GND
  DQ25_B  = M_J_CPU1_SB_DQ<25>
  VSS60  = GND
  DQS3_B_T  = M_J_CPU1_SB_DQS_DP<3>
  DQS3_B_C  = M_J_CPU1_SB_DQS_DN<3>
  VSS61  = GND
  DQ28_B  = M_J_CPU1_SB_DQ<28>
  VSS62  = GND
  DQ29_B  = M_J_CPU1_SB_DQ<29>
  VSS63  = GND
  RFU1  = NC
  VIN_BULK1  = P12V_MEM_CPU1
  VIN_BULK2  = P12V_MEM_CPU1
  \pwr_good||fail_n\  = PWRGD_CHJ_CPU1_DIMM
  HAS  = PD_CHJ_CPU1_DIMM_SAA
  RFU2  = NC
  RFU3  = NC
  VSS64  = GND
  DQ2_A  = M_J_CPU1_SA_DQ<2>
  VSS65  = GND
  DQ3_A  = M_J_CPU1_SA_DQ<3>
  VSS66  = GND
  \dqs5_a_c||tdqs5_a_c||dqs5_a_t||tdqs5_a_t\  = M_J_CPU1_SA_DQS_DN<5>
  \dqs5_a_t||tdqs5_a_t\  = M_J_CPU1_SA_DQS_DP<5>
  VSS67  = GND
  DQ6_A  = M_J_CPU1_SA_DQ<6>
  VSS68  = GND
  DQ7_A  = M_J_CPU1_SA_DQ<7>
  VSS69  = GND
  DQ10_A  = M_J_CPU1_SA_DQ<10>
  VSS70  = GND
  DQ11_A  = M_J_CPU1_SA_DQ<11>
  VSS71  = GND
  \dqs6_a_c||tdqs6_a_c||dqs6_a_t||tdqs6_a_t\  = M_J_CPU1_SA_DQS_DN<6>
  \dqs6_a_t||tdqs6_a_t\  = M_J_CPU1_SA_DQS_DP<6>
  VSS72  = GND
  DQ14_A  = M_J_CPU1_SA_DQ<14>
  VSS73  = GND
  DQ15_A  = M_J_CPU1_SA_DQ<15>
  VSS74  = GND
  DQ18_A  = M_J_CPU1_SA_DQ<18>
  VSS75  = GND
  DQ19_A  = M_J_CPU1_SA_DQ<19>
  VSS76  = GND
  \dqs7_a_c||tdqs7_a_c\  = M_J_CPU1_SA_DQS_DN<7>
  \dqs7_a_t||tdqs7_a_t\  = M_J_CPU1_SA_DQS_DP<7>
  VSS77  = GND
  DQ22_A  = M_J_CPU1_SA_DQ<22>
  VSS78  = GND
  DQ23_A  = M_J_CPU1_SA_DQ<23>
  VSS79  = GND
  DQ26_A  = M_J_CPU1_SA_DQ<26>
  VSS80  = GND
  DQ27_A  = M_J_CPU1_SA_DQ<27>
  VSS81  = GND
  \dqs8_a_c||tdqs8_a_c\  = M_J_CPU1_SA_DQS_DN<8>
  \dqs8_a_t||tdqs8_a_t\  = M_J_CPU1_SA_DQS_DP<8>
  VSS82  = GND
  DQ30_A  = M_J_CPU1_SA_DQ<30>
  VSS83  = GND
  DQ31_A  = M_J_CPU1_SA_DQ<31>
  VSS84  = GND
  CB2_A  = M_J_CPU1_SA_CB<2>
  VSS85  = GND
  CB3_A  = M_J_CPU1_SA_CB<3>
  VSS86  = GND
  \dqs9_a_c||tdqs9_a_c\  = M_J_CPU1_SA_DQS_DN<9>
  \dqs9_a_t||tdqs9_a_t\  = M_J_CPU1_SA_DQS_DP<9>
  VSS87  = GND
  CB6_A  = M_J_CPU1_SA_CB<6>
  VSS88  = GND
  CB7_A  = M_J_CPU1_SA_CB<7>
  VSS89  = GND
  RESET_N  = M_J_CPU1_RESET_N
  VSS90  = GND
  CS1_A_N  = M_J_CPU1_SA_CS_N<1>
  VSS91  = GND
  CA1_A  = M_J_CPU1_SA_CA<1>
  VSS92  = GND
  CA3_A  = M_J_CPU1_SA_CA<3>
  VSS93  = GND
  CA5_A  = M_J_CPU1_SA_CA<5>
  VSS94  = GND
  CK_T  = M_J_CPU1_CLK_DP<0>
  CK_C  = M_J_CPU1_CLK_DN<0>
  VSS95  = GND
  RFU4  = NC
  CA1_B  = M_J_CPU1_SB_CA<1>
  VSS96  = GND
  CA3_B  = M_J_CPU1_SB_CA<3>
  VSS97  = GND
  CA5_B  = M_J_CPU1_SB_CA<5>
  VSS98  = GND
  PAR_B  = M_J_CPU1_SB_PAR
  VSS99  = GND
  CS1_B_N  = M_J_CPU1_SB_CS_N<1>
  VSS100  = GND
  RFU5  = NC
  RFU6  = NC
  VSS101  = GND
  CB6_B  = M_J_CPU1_SB_CB<6>
  VSS102  = GND
  CB7_B  = M_J_CPU1_SB_CB<7>
  VSS103  = GND
  DQS4_B_C  = M_J_CPU1_SB_DQS_DN<4>
  DQS4_B_T  = M_J_CPU1_SB_DQS_DP<4>
  VSS104  = GND
  CB2_B  = M_J_CPU1_SB_CB<2>
  VSS105  = GND
  CB3_B  = M_J_CPU1_SB_CB<3>
  VSS106  = GND
  DQ2_B  = M_J_CPU1_SB_DQ<2>
  VSS107  = GND
  DQ3_B  = M_J_CPU1_SB_DQ<3>
  VSS108  = GND
  \dqs5_b_c||tdqs5_b_c\  = M_J_CPU1_SB_DQS_DN<5>
  \dqs5_b_t||tdqs5_b_t\  = M_J_CPU1_SB_DQS_DP<5>
  VSS109  = GND
  DQ6_B  = M_J_CPU1_SB_DQ<6>
  VSS110  = GND
  DQ7_B  = M_J_CPU1_SB_DQ<7>
  VSS111  = GND
  DQ10_B  = M_J_CPU1_SB_DQ<10>
  VSS112  = GND
  DQ11_B  = M_J_CPU1_SB_DQ<11>
  VSS113  = GND
  \dqs6_b_c||tdqs6_b_c\  = M_J_CPU1_SB_DQS_DN<6>
  \dqs6_b_t||tdqs6_b_t\  = M_J_CPU1_SB_DQS_DP<6>
  VSS114  = GND
  DQ14_B  = M_J_CPU1_SB_DQ<14>
  VSS115  = GND
  DQ15_B  = M_J_CPU1_SB_DQ<15>
  VSS116  = GND
  DQ18_B  = M_J_CPU1_SB_DQ<18>
  VSS117  = GND
  DQ19_B  = M_J_CPU1_SB_DQ<19>
  VSS118  = GND
  \dqs7_b_c||tdqs7_b_c\  = M_J_CPU1_SB_DQS_DN<7>
  \dqs7_b_t||tdqs7_b_t\  = M_J_CPU1_SB_DQS_DP<7>
  VSS119  = GND
  DQ22_B  = M_J_CPU1_SB_DQ<22>
  VSS120  = GND
  DQ23_B  = M_J_CPU1_SB_DQ<23>
  VSS121  = GND
  DQ26_B  = M_J_CPU1_SB_DQ<26>
  VSS122  = GND
  DQ27_B  = M_J_CPU1_SB_DQ<27>
  VSS123  = GND
  \dqs8_b_c||tdqs8_b_c\  = M_J_CPU1_SB_DQS_DN<8>
  \dqs8_b_t||tdqs8_b_t\  = M_J_CPU1_SB_DQS_DP<8>
  VSS124  = GND
  DQ30_B  = M_J_CPU1_SB_DQ<30>
  VSS125  = GND
  DQ31_B  = M_J_CPU1_SB_DQ<31>
  VSS126  = GND
  G1  = GND
  G2  = GND
  G3  = GND

(kicad_pcb
	(version 20260206)
	(generator "pcbnew")
	(generator_version "10.0")
	(general
		(thickness 1.6)
		(legacy_teardrops no)
	)
	(paper "A4")
	(title_block
		(title "04192023_DAF0TMB3IC0_F0TG_MB_C_brd_V02_OCP.brd")
		(comment 1 "Grand Teton / footprint 1456 of 8354 (J29), pads 1-45 of 291")
	)
	(layers
		(0 "F.Cu" signal "TOP")
		(4 "In1.Cu" signal "GND")
		(6 "In2.Cu" signal "IN1")
		(8 "In3.Cu" signal "GND1")
		(10 "In4.Cu" signal "IN2")
		(12 "In5.Cu" signal "GND2")
		(14 "In6.Cu" signal "IN3")
		(16 "In7.Cu" signal "GND3")
		(18 "In8.Cu" signal "VCC")
		(20 "In9.Cu" signal "VCC1")
		(22 "In10.Cu" signal "GND4")
		(24 "In11.Cu" signal "IN4")
		(26 "In12.Cu" signal "GND5")
		(28 "In13.Cu" signal "IN5")
		(30 "In14.Cu" signal "GND6")
		(32 "In15.Cu" signal "IN6")
		(34 "In16.Cu" signal "GND7")
		(2 "B.Cu" signal "BOTTOM")
		(9 "F.Adhes" user "F.Adhesive")
		(11 "B.Adhes" user "B.Adhesive")
		(13 "F.Paste" user "Package Geometry/Pastemask Top")
		(15 "B.Paste" user "Package Geometry/Pastemask Bottom")
		(5 "F.SilkS" user "Ref Des/Silkscreen Top")
		(7 "B.SilkS" user "Ref Des/Silkscreen Bottom")
		(1 "F.Mask" user "Board Geometry/Soldermask Top")
		(3 "B.Mask" user "Board Geometry/Soldermask Bottom")
		(17 "Dwgs.User" user "User.Drawings")
		(19 "Cmts.User" user "User.Comments")
		(21 "Eco1.User" user "User.Eco1")
		(23 "Eco2.User" user "User.Eco2")
		(25 "Edge.Cuts" user "Board Geometry/Outline")
		(27 "Margin" user)
		(31 "F.CrtYd" user "Package Geometry/Place Bound Top")
		(29 "B.CrtYd" user "Package Geometry/Place Bound Bottom")
		(35 "F.Fab" user "Ref Des/Assembly Top")
		(33 "B.Fab" user "Ref Des/Assembly Bottom")
	)
	(footprint ""
		(layer "F.Cu")
		(at 189.110112 -255.560322 180)
		(property "Reference" "J29"
			(at -2.7178 -81.857088 0)
			(unlocked yes)
			(layer "F.SilkS")
			(effects
				(font
					(size 0.7874 0.5842)
					(thickness 0.1524)
				)
			)
		)
		(property "Value" ""
			(at 0 0 180)
			(layer "F.Fab")
			(effects
				(font
					(size 1.27 1.27)
				)
			)
		)
		(duplicate_pad_numbers_are_jumpers no)
		(pad "1" smd rect
			(at -2.050034 -63.324994 90)
			(size 0.519938 1.4986)
			(layers "F.Cu" "F.Mask" "F.Paste")
			(net "P12V_MEM_CPU1")
		)
		(pad "2" smd rect
			(at -2.050034 -62.47511 90)
			(size 0.519938 1.4986)
			(layers "F.Cu" "F.Mask" "F.Paste")
			(net "Net_2382")
		)
		(pad "3" smd rect
			(at -2.050034 -61.624972 90)
			(size 0.519938 1.4986)
			(layers "F.Cu" "F.Mask" "F.Paste")
			(net "P3V3_AUX")
		)
		(pad "4" smd rect
			(at -2.050034 -60.775088 90)
			(size 0.519938 1.4986)
			(layers "F.Cu" "F.Mask" "F.Paste")
			(net "I3C_SPD_DDRJ_CPU1_SCL")
		)
		(pad "5" smd rect
			(at -2.050034 -59.92495 90)
			(size 0.519938 1.4986)
			(layers "F.Cu" "F.Mask" "F.Paste")
			(net "I3C_SPD_DDRJ_CPU1_SDA")
		)
		(pad "6" smd rect
			(at -2.050034 -59.075066 90)
			(size 0.519938 1.4986)
			(layers "F.Cu" "F.Mask" "F.Paste")
			(net "GND")
		)
		(pad "7" smd rect
			(at -2.050034 -58.224928 90)
			(size 0.519938 1.4986)
			(layers "F.Cu" "F.Mask" "F.Paste")
			(net "M_J_CPU1_SA_DQ<0>")
		)
		(pad "8" smd rect
			(at -2.050034 -57.375044 90)
			(size 0.519938 1.4986)
			(layers "F.Cu" "F.Mask" "F.Paste")
			(net "GND")
		)
		(pad "9" smd rect
			(at -2.050034 -56.524906 90)
			(size 0.519938 1.4986)
			(layers "F.Cu" "F.Mask" "F.Paste")
			(net "M_J_CPU1_SA_DQ<1>")
		)
		(pad "10" smd rect
			(at -2.050034 -55.675022 90)
			(size 0.519938 1.4986)
			(layers "F.Cu" "F.Mask" "F.Paste")
			(net "GND")
		)
		(pad "11" smd rect
			(at -2.050034 -54.824884 90)
			(size 0.519938 1.4986)
			(layers "F.Cu" "F.Mask" "F.Paste")
			(net "M_J_CPU1_SA_DQS_DP<0>")
		)
		(pad "12" smd rect
			(at -2.050034 -53.975 90)
			(size 0.519938 1.4986)
			(layers "F.Cu" "F.Mask" "F.Paste")
			(net "M_J_CPU1_SA_DQS_DN<0>")
		)
		(pad "13" smd rect
			(at -2.050034 -53.125116 90)
			(size 0.519938 1.4986)
			(layers "F.Cu" "F.Mask" "F.Paste")
			(net "GND")
		)
		(pad "14" smd rect
			(at -2.050034 -52.274978 90)
			(size 0.519938 1.4986)
			(layers "F.Cu" "F.Mask" "F.Paste")
			(net "M_J_CPU1_SA_DQ<4>")
		)
		(pad "15" smd rect
			(at -2.050034 -51.425094 90)
			(size 0.519938 1.4986)
			(layers "F.Cu" "F.Mask" "F.Paste")
			(net "GND")
		)
		(pad "16" smd rect
			(at -2.050034 -50.574956 90)
			(size 0.519938 1.4986)
			(layers "F.Cu" "F.Mask" "F.Paste")
			(net "M_J_CPU1_SA_DQ<5>")
		)
		(pad "17" smd rect
			(at -2.050034 -49.725072 90)
			(size 0.519938 1.4986)
			(layers "F.Cu" "F.Mask" "F.Paste")
			(net "GND")
		)
		(pad "18" smd rect
			(at -2.050034 -48.874934 90)
			(size 0.519938 1.4986)
			(layers "F.Cu" "F.Mask" "F.Paste")
			(net "M_J_CPU1_SA_DQ<8>")
		)
		(pad "19" smd rect
			(at -2.050034 -48.02505 90)
			(size 0.519938 1.4986)
			(layers "F.Cu" "F.Mask" "F.Paste")
			(net "GND")
		)
		(pad "20" smd rect
			(at -2.050034 -47.174912 90)
			(size 0.519938 1.4986)
			(layers "F.Cu" "F.Mask" "F.Paste")
			(net "M_J_CPU1_SA_DQ<9>")
		)
		(pad "21" smd rect
			(at -2.050034 -46.325028 90)
			(size 0.519938 1.4986)
			(layers "F.Cu" "F.Mask" "F.Paste")
			(net "GND")
		)
		(pad "22" smd rect
			(at -2.050034 -45.47489 90)
			(size 0.519938 1.4986)
			(layers "F.Cu" "F.Mask" "F.Paste")
			(net "M_J_CPU1_SA_DQS_DP<1>")
		)
		(pad "23" smd rect
			(at -2.050034 -44.625006 90)
			(size 0.519938 1.4986)
			(layers "F.Cu" "F.Mask" "F.Paste")
			(net "M_J_CPU1_SA_DQS_DN<1>")
		)
		(pad "24" smd rect
			(at -2.050034 -43.775122 90)
			(size 0.519938 1.4986)
			(layers "F.Cu" "F.Mask" "F.Paste")
			(net "GND")
		)
		(pad "25" smd rect
			(at -2.050034 -42.924984 90)
			(size 0.519938 1.4986)
			(layers "F.Cu" "F.Mask" "F.Paste")
			(net "M_J_CPU1_SA_DQ<12>")
		)
		(pad "26" smd rect
			(at -2.050034 -42.0751 90)
			(size 0.519938 1.4986)
			(layers "F.Cu" "F.Mask" "F.Paste")
			(net "GND")
		)
		(pad "27" smd rect
			(at -2.050034 -41.224962 90)
			(size 0.519938 1.4986)
			(layers "F.Cu" "F.Mask" "F.Paste")
			(net "M_J_CPU1_SA_DQ<13>")
		)
		(pad "28" smd rect
			(at -2.050034 -40.375078 90)
			(size 0.519938 1.4986)
			(layers "F.Cu" "F.Mask" "F.Paste")
			(net "GND")
		)
		(pad "29" smd rect
			(at -2.050034 -39.52494 90)
			(size 0.519938 1.4986)
			(layers "F.Cu" "F.Mask" "F.Paste")
			(net "M_J_CPU1_SA_DQ<16>")
		)
		(pad "30" smd rect
			(at -2.050034 -38.675056 90)
			(size 0.519938 1.4986)
			(layers "F.Cu" "F.Mask" "F.Paste")
			(net "GND")
		)
		(pad "31" smd rect
			(at -2.050034 -37.824918 90)
			(size 0.519938 1.4986)
			(layers "F.Cu" "F.Mask" "F.Paste")
			(net "M_J_CPU1_SA_DQ<17>")
		)
		(pad "32" smd rect
			(at -2.050034 -36.975034 90)
			(size 0.519938 1.4986)
			(layers "F.Cu" "F.Mask" "F.Paste")
			(net "GND")
		)
		(pad "33" smd rect
			(at -2.050034 -36.124896 90)
			(size 0.519938 1.4986)
			(layers "F.Cu" "F.Mask" "F.Paste")
			(net "M_J_CPU1_SA_DQS_DP<2>")
		)
		(pad "34" smd rect
			(at -2.050034 -35.275012 90)
			(size 0.519938 1.4986)
			(layers "F.Cu" "F.Mask" "F.Paste")
			(net "M_J_CPU1_SA_DQS_DN<2>")
		)
		(pad "35" smd rect
			(at -2.050034 -34.425128 90)
			(size 0.519938 1.4986)
			(layers "F.Cu" "F.Mask" "F.Paste")
			(net "GND")
		)
		(pad "36" smd rect
			(at -2.050034 -33.57499 90)
			(size 0.519938 1.4986)
			(layers "F.Cu" "F.Mask" "F.Paste")
			(net "M_J_CPU1_SA_DQ<20>")
		)
		(pad "37" smd rect
			(at -2.050034 -32.725106 90)
			(size 0.519938 1.4986)
			(layers "F.Cu" "F.Mask" "F.Paste")
			(net "GND")
		)
		(pad "38" smd rect
			(at -2.050034 -31.874968 90)
			(size 0.519938 1.4986)
			(layers "F.Cu" "F.Mask" "F.Paste")
			(net "M_J_CPU1_SA_DQ<21>")
		)
		(pad "39" smd rect
			(at -2.050034 -31.025084 90)
			(size 0.519938 1.4986)
			(layers "F.Cu" "F.Mask" "F.Paste")
			(net "GND")
		)
		(pad "40" smd rect
			(at -2.050034 -30.174946 90)
			(size 0.519938 1.4986)
			(layers "F.Cu" "F.Mask" "F.Paste")
			(net "M_J_CPU1_SA_DQ<24>")
		)
		(pad "41" smd rect
			(at -2.050034 -29.325062 90)
			(size 0.519938 1.4986)
			(layers "F.Cu" "F.Mask" "F.Paste")
			(net "GND")
		)
		(pad "42" smd rect
			(at -2.050034 -28.474924 90)
			(size 0.519938 1.4986)
			(layers "F.Cu" "F.Mask" "F.Paste")
			(net "M_J_CPU1_SA_DQ<25>")
		)
		(pad "43" smd rect
			(at -2.050034 -27.62504 90)
			(size 0.519938 1.4986)
			(layers "F.Cu" "F.Mask" "F.Paste")
			(net "GND")
		)
		(pad "44" smd rect
			(at -2.050034 -26.774902 90)
			(size 0.519938 1.4986)
			(layers "F.Cu" "F.Mask" "F.Paste")
			(net "M_J_CPU1_SA_DQS_DP<3>")
		)
		(pad "45" smd rect
			(at -2.050034 -25.925018 90)
			(size 0.519938 1.4986)
			(layers "F.Cu" "F.Mask" "F.Paste")
			(net "M_J_CPU1_SA_DQS_DN<3>")
		)
	)
)
